(kicad_pcb
	(version 20260206)
	(generator "pcbnew")
	(generator_version "10.0")
	(general
		(thickness 1.6)
		(legacy_teardrops no)
	)
	(paper "A4")
	(title_block
		(title "Wiwynn_Tioga_Pass_MB.brd")
		(comment 1 "Tioga Pass / footprints 964-970 of 4770")
	)
	(layers
		(0 "F.Cu" signal "TOP")
		(4 "In1.Cu" signal "L2GND")
		(6 "In2.Cu" signal "L3")
		(8 "In3.Cu" signal "L4GND")
		(10 "In4.Cu" signal "L5")
		(12 "In5.Cu" signal "L6GND")
		(14 "In6.Cu" signal "L7VCC")
		(16 "In7.Cu" signal "L8VCC")
		(18 "In8.Cu" signal "L9GND")
		(20 "In9.Cu" signal "L10")
		(22 "In10.Cu" signal "L11GND")
		(24 "In11.Cu" signal "L12")
		(26 "In12.Cu" signal "L13GND")
		(2 "B.Cu" signal "BOTTOM")
		(9 "F.Adhes" user "F.Adhesive")
		(11 "B.Adhes" user "B.Adhesive")
		(13 "F.Paste" user "Package Geometry/Pastemask Top")
		(15 "B.Paste" user "Package Geometry/Pastemask Bottom")
		(5 "F.SilkS" user "Ref Des/Silkscreen Top")
		(7 "B.SilkS" user "Ref Des/Silkscreen Bottom")
		(1 "F.Mask" user "Board Geometry/Soldermask Top")
		(3 "B.Mask" user "Board Geometry/Soldermask Bottom")
		(17 "Dwgs.User" user "User.Drawings")
		(19 "Cmts.User" user "User.Comments")
		(21 "Eco1.User" user "User.Eco1")
		(23 "Eco2.User" user "User.Eco2")
		(25 "Edge.Cuts" user "Board Geometry/Outline")
		(27 "Margin" user)
		(31 "F.CrtYd" user "Package Geometry/Place Bound Top")
		(29 "B.CrtYd" user "Package Geometry/Place Bound Bottom")
		(35 "F.Fab" user "Ref Des/Assembly Top")
		(33 "B.Fab" user "Ref Des/Assembly Bottom")
	)
	(footprint ""
		(layer "F.Cu")
		(at 455.6125 -30.48 -90)
		(property "Reference" "R9F28"
			(at 0 0 270)
			(layer "F.SilkS")
			(hide yes)
			(effects
				(font
					(size 1.27 1.27)
				)
			)
		)
		(property "Value" ""
			(at 0 0 270)
			(layer "F.Fab")
			(effects
				(font
					(size 1.27 1.27)
				)
			)
		)
		(duplicate_pad_numbers_are_jumpers no)
		(fp_poly
			(pts
				(xy -0.2794 -0.1016) (xy 0.2794 -0.1016) (xy 0.2794 0.9906) (xy -0.2794 0.9906)
			)
			(stroke
				(width 0)
				(type default)
			)
			(fill no)
			(layer "F.CrtYd")
		)
		(fp_line
			(start -0.2794 0.9906)
			(end 0.2794 0.9906)
			(stroke
				(width 0.1)
				(type default)
			)
			(layer "F.Fab")
		)
		(fp_line
			(start 0.2794 0.9906)
			(end 0.2794 -0.1016)
			(stroke
				(width 0.1)
				(type default)
			)
			(layer "F.Fab")
		)
		(fp_line
			(start -0.2794 -0.1016)
			(end -0.2794 0.9906)
			(stroke
				(width 0.1)
				(type default)
			)
			(layer "F.Fab")
		)
		(fp_line
			(start 0.2794 -0.1016)
			(end -0.2794 -0.1016)
			(stroke
				(width 0.1)
				(type default)
			)
			(layer "F.Fab")
		)
		(pad "1" smd rect
			(at 0 0 270)
			(size 0.508 0.508)
			(layers "F.Cu" "F.Mask" "F.Paste")
			(net "P3V3_STBY")
		)
		(pad "2" smd rect
			(at 0 0.889 270)
			(size 0.508 0.508)
			(layers "F.Cu" "F.Mask" "F.Paste")
			(net "FM_RED_LED_ANODE")
		)
		(zone
			(layer "F.Cu")
			(hatch none 0.5)
			(connect_pads
				(clearance 0)
			)
			(min_thickness 0.25)
			(keepout
				(tracks not_allowed)
				(vias allowed)
				(pads allowed)
				(copperpour not_allowed)
				(footprints allowed)
			)
			(placement
				(enabled no)
				(sheetname "")
			)
			(fill
				(thermal_gap 0.5)
				(thermal_bridge_width 0.5)
				(island_removal_mode 0)
			)
			(polygon
				(pts
					(xy 454.9775 -30.734) (xy 454.9775 -30.226) (xy 455.3585 -30.226) (xy 455.3585 -30.734)
				)
			)
		)
		(zone
			(layer "F.Cu")
			(hatch none 0.5)
			(connect_pads
				(clearance 0)
			)
			(min_thickness 0.25)
			(keepout
				(tracks allowed)
				(vias not_allowed)
				(pads allowed)
				(copperpour not_allowed)
				(footprints allowed)
			)
			(placement
				(enabled no)
				(sheetname "")
			)
			(fill
				(thermal_gap 0.5)
				(thermal_bridge_width 0.5)
				(island_removal_mode 0)
			)
			(polygon
				(pts
					(xy 455.3585 -30.734) (xy 455.3585 -30.226) (xy 454.9775 -30.226) (xy 454.9775 -30.734)
				)
			)
		)
	)
	(footprint ""
		(layer "F.Cu")
		(at 102.258368 -84.7598)
		(property "Reference" "C2D6"
			(at 0 0 0)
			(layer "F.SilkS")
			(hide yes)
			(effects
				(font
					(size 1.27 1.27)
				)
			)
		)
		(property "Value" ""
			(at 0 0 0)
			(layer "F.Fab")
			(effects
				(font
					(size 1.27 1.27)
				)
			)
		)
		(duplicate_pad_numbers_are_jumpers no)
		(fp_poly
			(pts
				(xy -0.4953 -0.2032) (xy 0.4953 -0.2032) (xy 0.4953 1.6002) (xy -0.4953 1.6002)
			)
			(stroke
				(width 0)
				(type default)
			)
			(fill no)
			(layer "F.CrtYd")
		)
		(fp_line
			(start -0.4953 -0.2032)
			(end 0.4953 -0.2032)
			(stroke
				(width 0.1)
				(type default)
			)
			(layer "F.Fab")
		)
		(fp_line
			(start -0.4953 1.6002)
			(end -0.4953 -0.2032)
			(stroke
				(width 0.1)
				(type default)
			)
			(layer "F.Fab")
		)
		(fp_line
			(start 0.4953 -0.2032)
			(end 0.4953 1.6002)
			(stroke
				(width 0.1)
				(type default)
			)
			(layer "F.Fab")
		)
		(fp_line
			(start 0.4953 1.6002)
			(end -0.4953 1.6002)
			(stroke
				(width 0.1)
				(type default)
			)
			(layer "F.Fab")
		)
		(pad "1" smd rect
			(at 0 0)
			(size 0.762 0.889)
			(layers "F.Cu" "F.Mask" "F.Paste")
			(net "PVDDQ_KLM")
		)
		(pad "2" smd rect
			(at 0 1.397)
			(size 0.762 0.889)
			(layers "F.Cu" "F.Mask" "F.Paste")
			(net "GND")
		)
		(zone
			(layer "F.Cu")
			(hatch none 0.5)
			(connect_pads
				(clearance 0)
			)
			(min_thickness 0.25)
			(keepout
				(tracks not_allowed)
				(vias allowed)
				(pads allowed)
				(copperpour not_allowed)
				(footprints allowed)
			)
			(placement
				(enabled no)
				(sheetname "")
			)
			(fill
				(thermal_gap 0.5)
				(thermal_bridge_width 0.5)
				(island_removal_mode 0)
			)
			(polygon
				(pts
					(xy 101.877368 -84.3153) (xy 102.639368 -84.3153) (xy 102.639368 -83.8073) (xy 101.877368 -83.8073)
				)
			)
		)
	)
	(footprint ""
		(layer "F.Cu")
		(at 369.2906 -99.2124)
		(property "Reference" "R7C6"
			(at 0 0 0)
			(layer "F.SilkS")
			(hide yes)
			(effects
				(font
					(size 1.27 1.27)
				)
			)
		)
		(property "Value" ""
			(at 0 0 0)
			(layer "F.Fab")
			(effects
				(font
					(size 1.27 1.27)
				)
			)
		)
		(duplicate_pad_numbers_are_jumpers no)
		(fp_poly
			(pts
				(xy -0.4953 -0.2032) (xy 0.4953 -0.2032) (xy 0.4953 1.6002) (xy -0.4953 1.6002)
			)
			(stroke
				(width 0)
				(type default)
			)
			(fill no)
			(layer "F.CrtYd")
		)
		(fp_line
			(start -0.4953 -0.2032)
			(end 0.4953 -0.2032)
			(stroke
				(width 0.1)
				(type default)
			)
			(layer "F.Fab")
		)
		(fp_line
			(start -0.4953 1.6002)
			(end -0.4953 -0.2032)
			(stroke
				(width 0.1)
				(type default)
			)
			(layer "F.Fab")
		)
		(fp_line
			(start 0.4953 -0.2032)
			(end 0.4953 1.6002)
			(stroke
				(width 0.1)
				(type default)
			)
			(layer "F.Fab")
		)
		(fp_line
			(start 0.4953 1.6002)
			(end -0.4953 1.6002)
			(stroke
				(width 0.1)
				(type default)
			)
			(layer "F.Fab")
		)
		(pad "1" smd rect
			(at 0 0)
			(size 0.762 0.889)
			(layers "F.Cu" "F.Mask" "F.Paste")
			(net "XTAL_33K_RTC1")
		)
		(pad "2" smd rect
			(at 0 1.397)
			(size 0.762 0.889)
			(layers "F.Cu" "F.Mask" "F.Paste")
			(net "XTAL_33K_RTC2")
		)
		(zone
			(layer "F.Cu")
			(hatch none 0.5)
			(connect_pads
				(clearance 0)
			)
			(min_thickness 0.25)
			(keepout
				(tracks not_allowed)
				(vias allowed)
				(pads allowed)
				(copperpour not_allowed)
				(footprints allowed)
			)
			(placement
				(enabled no)
				(sheetname "")
			)
			(fill
				(thermal_gap 0.5)
				(thermal_bridge_width 0.5)
				(island_removal_mode 0)
			)
			(polygon
				(pts
					(xy 368.9096 -98.2599) (xy 369.6716 -98.2599) (xy 369.6716 -98.7679) (xy 368.9096 -98.7679)
				)
			)
		)
		(zone
			(layer "F.Cu")
			(hatch none 0.5)
			(connect_pads
				(clearance 0)
			)
			(min_thickness 0.25)
			(keepout
				(tracks allowed)
				(vias not_allowed)
				(pads allowed)
				(copperpour not_allowed)
				(footprints allowed)
			)
			(placement
				(enabled no)
				(sheetname "")
			)
			(fill
				(thermal_gap 0.5)
				(thermal_bridge_width 0.5)
				(island_removal_mode 0)
			)
			(polygon
				(pts
					(xy 369.6716 -98.2599) (xy 369.6716 -98.7679) (xy 368.9096 -98.7679) (xy 368.9096 -98.2599)
				)
			)
		)
	)
	(footprint ""
		(layer "F.Cu")
		(at 28.829 -83.1342 90)
		(property "Reference" "C1D10"
			(at 0 0 90)
			(layer "F.SilkS")
			(hide yes)
			(effects
				(font
					(size 1.27 1.27)
				)
			)
		)
		(property "Value" ""
			(at 0 0 90)
			(layer "F.Fab")
			(effects
				(font
					(size 1.27 1.27)
				)
			)
		)
		(duplicate_pad_numbers_are_jumpers no)
		(fp_rect
			(start -0.3048 0.9906)
			(end 0.3048 -0.1016)
			(stroke
				(width 0)
				(type default)
			)
			(fill no)
			(layer "F.CrtYd")
		)
		(fp_line
			(start 0.3048 -0.1016)
			(end -0.3048 -0.1016)
			(stroke
				(width 0.1)
				(type default)
			)
			(layer "F.Fab")
		)
		(fp_line
			(start -0.3048 -0.1016)
			(end -0.3048 0.9906)
			(stroke
				(width 0.1)
				(type default)
			)
			(layer "F.Fab")
		)
		(fp_line
			(start 0.3048 0.9906)
			(end 0.3048 -0.1016)
			(stroke
				(width 0.1)
				(type default)
			)
			(layer "F.Fab")
		)
		(fp_line
			(start -0.3048 0.9906)
			(end 0.3048 0.9906)
			(stroke
				(width 0.1)
				(type default)
			)
			(layer "F.Fab")
		)
		(pad "1" smd rect
			(at 0 0 90)
			(size 0.508 0.508)
			(layers "F.Cu" "F.Mask" "F.Paste")
			(net "VR_PVCCIN_CPU1_PH4_BOOT")
		)
		(pad "2" smd rect
			(at 0 0.889 90)
			(size 0.508 0.508)
			(layers "F.Cu" "F.Mask" "F.Paste")
			(net "VR_PVCCIN_CPU1_PH4_PHASE")
		)
		(zone
			(layer "F.Cu")
			(hatch none 0.5)
			(connect_pads
				(clearance 0)
			)
			(min_thickness 0.25)
			(keepout
				(tracks not_allowed)
				(vias allowed)
				(pads allowed)
				(copperpour not_allowed)
				(footprints allowed)
			)
			(placement
				(enabled no)
				(sheetname "")
			)
			(fill
				(thermal_gap 0.5)
				(thermal_bridge_width 0.5)
				(island_removal_mode 0)
			)
			(polygon
				(pts
					(xy 29.464 -82.8802) (xy 29.464 -83.3882) (xy 29.083 -83.3882) (xy 29.083 -82.8802)
				)
			)
		)
		(zone
			(layer "F.Cu")
			(hatch none 0.5)
			(connect_pads
				(clearance 0)
			)
			(min_thickness 0.25)
			(keepout
				(tracks allowed)
				(vias not_allowed)
				(pads allowed)
				(copperpour not_allowed)
				(footprints allowed)
			)
			(placement
				(enabled no)
				(sheetname "")
			)
			(fill
				(thermal_gap 0.5)
				(thermal_bridge_width 0.5)
				(island_removal_mode 0)
			)
			(polygon
				(pts
					(xy 29.464 -82.8802) (xy 29.464 -83.3882) (xy 29.083 -83.3882) (xy 29.083 -82.8802)
				)
			)
		)
	)
	(footprint ""
		(layer "F.Cu")
		(at 179.959 -7.366 180)
		(property "Reference" "R4G14"
			(at 0 0 180)
			(layer "F.SilkS")
			(hide yes)
			(effects
				(font
					(size 1.27 1.27)
				)
			)
		)
		(property "Value" ""
			(at 0 0 180)
			(layer "F.Fab")
			(effects
				(font
					(size 1.27 1.27)
				)
			)
		)
		(duplicate_pad_numbers_are_jumpers no)
		(fp_rect
			(start 0.2794 -0.1016)
			(end -0.2794 0.9906)
			(stroke
				(width 0)
				(type default)
			)
			(fill no)
			(layer "F.CrtYd")
		)
		(fp_line
			(start 0.2794 0.9906)
			(end 0.2794 -0.1016)
			(stroke
				(width 0.1)
				(type default)
			)
			(layer "F.Fab")
		)
		(fp_line
			(start 0.2794 -0.1016)
			(end -0.2794 -0.1016)
			(stroke
				(width 0.1)
				(type default)
			)
			(layer "F.Fab")
		)
		(fp_line
			(start -0.2794 0.9906)
			(end 0.2794 0.9906)
			(stroke
				(width 0.1)
				(type default)
			)
			(layer "F.Fab")
		)
		(fp_line
			(start -0.2794 -0.1016)
			(end -0.2794 0.9906)
			(stroke
				(width 0.1)
				(type default)
			)
			(layer "F.Fab")
		)
		(pad "1" smd rect
			(at 0 0 180)
			(size 0.508 0.508)
			(layers "F.Cu" "F.Mask" "F.Paste")
			(net "P3V3_STBY")
		)
		(pad "2" smd rect
			(at 0 0.889 180)
			(size 0.508 0.508)
			(layers "F.Cu" "F.Mask" "F.Paste")
			(net "PWRGD_PVPP_GHJ_R")
		)
		(zone
			(layer "F.Cu")
			(hatch none 0.5)
			(connect_pads
				(clearance 0)
			)
			(min_thickness 0.25)
			(keepout
				(tracks not_allowed)
				(vias allowed)
				(pads allowed)
				(copperpour not_allowed)
				(footprints allowed)
			)
			(placement
				(enabled no)
				(sheetname "")
			)
			(fill
				(thermal_gap 0.5)
				(thermal_bridge_width 0.5)
				(island_removal_mode 0)
			)
			(polygon
				(pts
					(xy 179.705 -7.62) (xy 180.213 -7.62) (xy 180.213 -8.001) (xy 179.705 -8.001)
				)
			)
		)
		(zone
			(layer "F.Cu")
			(hatch none 0.5)
			(connect_pads
				(clearance 0)
			)
			(min_thickness 0.25)
			(keepout
				(tracks allowed)
				(vias not_allowed)
				(pads allowed)
				(copperpour not_allowed)
				(footprints allowed)
			)
			(placement
				(enabled no)
				(sheetname "")
			)
			(fill
				(thermal_gap 0.5)
				(thermal_bridge_width 0.5)
				(island_removal_mode 0)
			)
			(polygon
				(pts
					(xy 179.705 -7.62) (xy 180.213 -7.62) (xy 180.213 -8.001) (xy 179.705 -8.001)
				)
			)
		)
	)
	(footprint ""
		(layer "F.Cu")
		(at 337.1215 -127.254 90)
		(property "Reference" "R7B18"
			(at 0 0 90)
			(layer "F.SilkS")
			(hide yes)
			(effects
				(font
					(size 1.27 1.27)
				)
			)
		)
		(property "Value" ""
			(at 0 0 90)
			(layer "F.Fab")
			(effects
				(font
					(size 1.27 1.27)
				)
			)
		)
		(duplicate_pad_numbers_are_jumpers no)
		(fp_poly
			(pts
				(xy -0.2794 -0.1016) (xy 0.2794 -0.1016) (xy 0.2794 0.9906) (xy -0.2794 0.9906)
			)
			(stroke
				(width 0)
				(type default)
			)
			(fill no)
			(layer "F.CrtYd")
		)
		(fp_line
			(start 0.2794 -0.1016)
			(end -0.2794 -0.1016)
			(stroke
				(width 0.1)
				(type default)
			)
			(layer "F.Fab")
		)
		(fp_line
			(start -0.2794 -0.1016)
			(end -0.2794 0.9906)
			(stroke
				(width 0.1)
				(type default)
			)
			(layer "F.Fab")
		)
		(fp_line
			(start 0.2794 0.9906)
			(end 0.2794 -0.1016)
			(stroke
				(width 0.1)
				(type default)
			)
			(layer "F.Fab")
		)
		(fp_line
			(start -0.2794 0.9906)
			(end 0.2794 0.9906)
			(stroke
				(width 0.1)
				(type default)
			)
			(layer "F.Fab")
		)
		(pad "1" smd rect
			(at 0 0 90)
			(size 0.508 0.508)
			(layers "F.Cu" "F.Mask" "F.Paste")
			(net "VSENSE_PVPP_DEF")
		)
		(pad "2" smd rect
			(at 0 0.889 90)
			(size 0.508 0.508)
			(layers "F.Cu" "F.Mask" "F.Paste")
			(net "VR_COMP_PVPP_DEF")
		)
		(zone
			(layer "F.Cu")
			(hatch none 0.5)
			(connect_pads
				(clearance 0)
			)
			(min_thickness 0.25)
			(keepout
				(tracks allowed)
				(vias not_allowed)
				(pads allowed)
				(copperpour not_allowed)
				(footprints allowed)
			)
			(placement
				(enabled no)
				(sheetname "")
			)
			(fill
				(thermal_gap 0.5)
				(thermal_bridge_width 0.5)
				(island_removal_mode 0)
			)
			(polygon
				(pts
					(xy 337.3755 -127) (xy 337.3755 -127.508) (xy 337.7565 -127.508) (xy 337.7565 -127)
				)
			)
		)
		(zone
			(layer "F.Cu")
			(hatch none 0.5)
			(connect_pads
				(clearance 0)
			)
			(min_thickness 0.25)
			(keepout
				(tracks not_allowed)
				(vias allowed)
				(pads allowed)
				(copperpour not_allowed)
				(footprints allowed)
			)
			(placement
				(enabled no)
				(sheetname "")
			)
			(fill
				(thermal_gap 0.5)
				(thermal_bridge_width 0.5)
				(island_removal_mode 0)
			)
			(polygon
				(pts
					(xy 337.7565 -127) (xy 337.7565 -127.508) (xy 337.3755 -127.508) (xy 337.3755 -127)
				)
			)
		)
	)
	(footprint ""
		(layer "F.Cu")
		(at 466.311996 2.8194 180)
		(property "Reference" "Q9G1"
			(at 2.54254 2.20091 0)
			(unlocked yes)
			(layer "F.SilkS")
			(effects
				(font
					(size 0.7874 0.5842)
					(thickness 0.1524)
				)
				(justify left)
			)
		)
		(property "Value" ""
			(at 0 0 180)
			(layer "F.Fab")
			(effects
				(font
					(size 1.27 1.27)
				)
			)
		)
		(duplicate_pad_numbers_are_jumpers no)
		(fp_circle
			(center -0.48641 -0.538734)
			(end -0.61341 -0.538734)
			(stroke
				(width 0.254)
				(type default)
			)
			(fill no)
			(layer "F.SilkS")
		)
		(fp_poly
			(pts
				(xy 0.2159 1.7526) (xy 1.5621 1.7526) (xy 1.5621 -0.4572) (xy 0.2159 -0.4572)
			)
			(stroke
				(width 0)
				(type default)
			)
			(fill no)
			(layer "F.CrtYd")
		)
		(fp_line
			(start 1.5621 1.75514)
			(end 1.5621 -0.45466)
			(stroke
				(width 0.1)
				(type default)
			)
			(layer "F.Fab")
		)
		(fp_line
			(start 1.5621 -0.45466)
			(end 0.2159 -0.45466)
			(stroke
				(width 0.1)
				(type default)
			)
			(layer "F.Fab")
		)
		(fp_line
			(start 0.2159 1.75514)
			(end 1.5621 1.75514)
			(stroke
				(width 0.1)
				(type default)
			)
			(layer "F.Fab")
		)
		(fp_line
			(start 0.2159 -0.45466)
			(end 0.2159 1.75514)
			(stroke
				(width 0.1)
				(type default)
			)
			(layer "F.Fab")
		)
		(fp_circle
			(center -0.508 -0.7874)
			(end -0.635 -0.7874)
			(stroke
				(width 0.254)
				(type default)
			)
			(fill no)
			(layer "F.Fab")
		)
		(pad "1" smd rect
			(at 0 0 180)
			(size 1.016 0.381)
			(layers "F.Cu" "F.Mask" "F.Paste")
			(net "GND")
		)
		(pad "2" smd rect
			(at 0 0.65024 180)
			(size 1.016 0.381)
			(layers "F.Cu" "F.Mask" "F.Paste")
			(net "FM_BATTERY_SENSE_EN_N")
		)
		(pad "3" smd rect
			(at 0 1.30048 180)
			(size 1.016 0.381)
			(layers "F.Cu" "F.Mask" "F.Paste")
			(net "P3V_BAT_SOURCE_R")
		)
		(pad "4" smd rect
			(at 1.778 1.30048 180)
			(size 1.016 0.381)
			(layers "F.Cu" "F.Mask" "F.Paste")
			(net "A_P3V_BAT_SCALED")
		)
		(pad "5" smd rect
			(at 1.778 0.65024 180)
			(size 1.016 0.381)
			(layers "F.Cu" "F.Mask" "F.Paste")
			(net "FM_BATTERY_SENSE_EN")
		)
		(pad "6" smd rect
			(at 1.778 0 180)
			(size 1.016 0.381)
			(layers "F.Cu" "F.Mask" "F.Paste")
			(net "FM_BATTERY_SENSE_EN")
		)
		(zone
			(layer "F.Cu")
			(hatch none 0.5)
			(connect_pads
				(clearance 0)
			)
			(min_thickness 0.25)
			(keepout
				(tracks allowed)
				(vias not_allowed)
				(pads allowed)
				(copperpour not_allowed)
				(footprints allowed)
			)
			(placement
				(enabled no)
				(sheetname "")
			)
			(fill
				(thermal_gap 0.5)
				(thermal_bridge_width 0.5)
				(island_removal_mode 0)
			)
			(polygon
				(pts
					(xy 465.041996 3.0099) (xy 464.025996 3.0099) (xy 464.025996 1.3208) (xy 465.041996 1.3208)
				)
			)
		)
		(zone
			(layer "F.Cu")
			(hatch none 0.5)
			(connect_pads
				(clearance 0)
			)
			(min_thickness 0.25)
			(keepout
				(tracks allowed)
				(vias not_allowed)
				(pads allowed)
				(copperpour not_allowed)
				(footprints allowed)
			)
			(placement
				(enabled no)
				(sheetname "")
			)
			(fill
				(thermal_gap 0.5)
				(thermal_bridge_width 0.5)
				(island_removal_mode 0)
			)
			(polygon
				(pts
					(xy 466.819996 3.0099) (xy 465.803996 3.0099) (xy 465.803996 1.3208) (xy 466.819996 1.3208)
				)
			)
		)
	)
)
